# T6G (Grand Teton) — schematic netlist excerpt (pin names and nets, part order shuffled) for the footprints in the layout excerpt that follows; sources: Cadence DE-HDL packaged netlist, KiCad conversion of 04192023_DAF0TMB3IC0_F0TG_MB_C_brd_V02_OCP.brd

J29  SCONN288_DDR506112002KQ  IO  pkg DDR288S_1-1VXC  page 107
  VIN_BULK0  = P12V_MEM_CPU1
  RFU0  = NC
  VIN_MGMT  = P3V3_AUX
  HSCL  = I3C_SPD_DDRJ_CPU1_SCL
  HSDA  = I3C_SPD_DDRJ_CPU1_SDA
  VSS0  = GND
  DQ0_A  = M_J_CPU1_SA_DQ<0>
  VSS1  = GND
  DQ1_A  = M_J_CPU1_SA_DQ<1>
  VSS2  = GND
  DQS0_A_T  = M_J_CPU1_SA_DQS_DP<0>
  DQS0_A_C  = M_J_CPU1_SA_DQS_DN<0>
  VSS3  = GND
  DQ4_A  = M_J_CPU1_SA_DQ<4>
  VSS4  = GND
  DQ5_A  = M_J_CPU1_SA_DQ<5>
  VSS5  = GND
  DQ8_A  = M_J_CPU1_SA_DQ<8>
  VSS6  = GND
  DQ9_A  = M_J_CPU1_SA_DQ<9>
  VSS7  = GND
  DQS1_A_T  = M_J_CPU1_SA_DQS_DP<1>
  DQS1_A_C  = M_J_CPU1_SA_DQS_DN<1>
  VSS8  = GND
  DQ12_A  = M_J_CPU1_SA_DQ<12>
  VSS9  = GND
  DQ13_A  = M_J_CPU1_SA_DQ<13>
  VSS10  = GND
  DQ16_A  = M_J_CPU1_SA_DQ<16>
  VSS11  = GND
  DQ17_A  = M_J_CPU1_SA_DQ<17>
  VSS12  = GND
  DQS2_A_T  = M_J_CPU1_SA_DQS_DP<2>
  DQS2_A_C  = M_J_CPU1_SA_DQS_DN<2>
  VSS13  = GND
  DQ20_A  = M_J_CPU1_SA_DQ<20>
  VSS14  = GND
  DQ21_A  = M_J_CPU1_SA_DQ<21>
  VSS15  = GND
  DQ24_A  = M_J_CPU1_SA_DQ<24>
  VSS16  = GND
  DQ25_A  = M_J_CPU1_SA_DQ<25>
  VSS17  = GND
  DQS3_A_T  = M_J_CPU1_SA_DQS_DP<3>
  DQS3_A_C  = M_J_CPU1_SA_DQS_DN<3>
  VSS18  = GND
  DQ28_A  = M_J_CPU1_SA_DQ<28>
  VSS19  = GND
  DQ29_A  = M_J_CPU1_SA_DQ<29>
  VSS20  = GND
  CB0_A  = M_J_CPU1_SA_CB<0>
  VSS21  = GND
  CB1_A  = M_J_CPU1_SA_CB<1>
  VSS22  = GND
  DQS4_A_T  = M_J_CPU1_SA_DQS_DP<4>
  DQS4_A_C  = M_J_CPU1_SA_DQS_DN<4>
  VSS23  = GND
  CB4_A  = M_J_CPU1_SA_CB<4>
  VSS24  = GND
  CB5_A  = M_J_CPU1_SA_CB<5>
  VSS25  = GND
  ALERT_N  = M_J_CPU1_ALERT_N
  VSS26  = GND
  CS0_A_N  = M_J_CPU1_SA_CS_N<0>
  VSS27  = GND
  CA0_A  = M_J_CPU1_SA_CA<0>
  VSS28  = GND
  CA2_A  = M_J_CPU1_SA_CA<2>
  VSS29  = GND
  CA4_A  = M_J_CPU1_SA_CA<4>
  VSS30  = GND
  CA6_A  = M_J_CPU1_SA_CA<6>
  VSS31  = GND
  PAR_A  = M_J_CPU1_SA_PAR
  VSS32  = GND
  CA0_B  = M_J_CPU1_SB_CA<0>
  VSS33  = GND
  CA2_B  = M_J_CPU1_SB_CA<2>
  VSS34  = GND
  CA4_B  = M_J_CPU1_SB_CA<4>
  VSS35  = GND
  CA6_B  = M_J_CPU1_SB_CA<6>
  VSS36  = GND
  CS0_B_N  = M_J_CPU1_SB_CS_N<0>
  VSS37  = GND
  \lbd||rsp_a_n\  = M_J_CPU1_SA_RSP<0>
  \lbs||rsp_b_n\  = M_J_CPU1_SB_RSP<0>
  VSS38  = GND
  CB4_B  = M_J_CPU1_SB_CB<4>
  VSS39  = GND
  CB5_B  = M_J_CPU1_SB_CB<5>
  VSS40  = GND
  \dqs9_b_t||tdqs9_b_t||dbi4_b_n\  = M_J_CPU1_SB_DQS_DP<9>
  \dqs9_b_c||tdqs9_b_c\  = M_J_CPU1_SB_DQS_DN<9>
  VSS41  = GND
  CB0_B  = M_J_CPU1_SB_CB<0>
  VSS42  = GND
  CB1_B  = M_J_CPU1_SB_CB<1>
  VSS43  = GND
  DQ0_B  = M_J_CPU1_SB_DQ<0>
  VSS44  = GND
  DQ1_B  = M_J_CPU1_SB_DQ<1>
  VSS45  = GND
  DQS0_B_T  = M_J_CPU1_SB_DQS_DP<0>
  DQS0_B_C  = M_J_CPU1_SB_DQS_DN<0>
  VSS46  = GND
  DQ4_B  = M_J_CPU1_SB_DQ<4>
  VSS47  = GND
  DQ5_B  = M_J_CPU1_SB_DQ<5>
  VSS48  = GND
  DQ8_B  = M_J_CPU1_SB_DQ<8>
  VSS49  = GND
  DQ9_B  = M_J_CPU1_SB_DQ<9>
  VSS50  = GND
  DQS1_B_T  = M_J_CPU1_SB_DQS_DP<1>
  DQS1_B_C  = M_J_CPU1_SB_DQS_DN<1>
  VSS51  = GND
  DQ12_B  = M_J_CPU1_SB_DQ<12>
  VSS52  = GND
  DQ13_B  = M_J_CPU1_SB_DQ<13>
  VSS53  = GND
  DQ16_B  = M_J_CPU1_SB_DQ<16>
  VSS54  = GND
  DQ17_B  = M_J_CPU1_SB_DQ<17>
  VSS55  = GND
  DQS2_B_T  = M_J_CPU1_SB_DQS_DP<2>
  DQS2_B_C  = M_J_CPU1_SB_DQS_DN<2>
  VSS56  = GND
  DQ20_B  = M_J_CPU1_SB_DQ<20>
  VSS57  = GND
  DQ21_B  = M_J_CPU1_SB_DQ<21>
  VSS58  = GND
  DQ24_B  = M_J_CPU1_SB_DQ<24>
  VSS59  = GND
  DQ25_B  = M_J_CPU1_SB_DQ<25>
  VSS60  = GND
  DQS3_B_T  = M_J_CPU1_SB_DQS_DP<3>
  DQS3_B_C  = M_J_CPU1_SB_DQS_DN<3>
  VSS61  = GND
  DQ28_B  = M_J_CPU1_SB_DQ<28>
  VSS62  = GND
  DQ29_B  = M_J_CPU1_SB_DQ<29>
  VSS63  = GND
  RFU1  = NC
  VIN_BULK1  = P12V_MEM_CPU1
  VIN_BULK2  = P12V_MEM_CPU1
  \pwr_good||fail_n\  = PWRGD_CHJ_CPU1_DIMM
  HAS  = PD_CHJ_CPU1_DIMM_SAA
  RFU2  = NC
  RFU3  = NC
  VSS64  = GND
  DQ2_A  = M_J_CPU1_SA_DQ<2>
  VSS65  = GND
  DQ3_A  = M_J_CPU1_SA_DQ<3>
  VSS66  = GND
  \dqs5_a_c||tdqs5_a_c||dqs5_a_t||tdqs5_a_t\  = M_J_CPU1_SA_DQS_DN<5>
  \dqs5_a_t||tdqs5_a_t\  = M_J_CPU1_SA_DQS_DP<5>
  VSS67  = GND
  DQ6_A  = M_J_CPU1_SA_DQ<6>
  VSS68  = GND
  DQ7_A  = M_J_CPU1_SA_DQ<7>
  VSS69  = GND
  DQ10_A  = M_J_CPU1_SA_DQ<10>
  VSS70  = GND
  DQ11_A  = M_J_CPU1_SA_DQ<11>
  VSS71  = GND
  \dqs6_a_c||tdqs6_a_c||dqs6_a_t||tdqs6_a_t\  = M_J_CPU1_SA_DQS_DN<6>
  \dqs6_a_t||tdqs6_a_t\  = M_J_CPU1_SA_DQS_DP<6>
  VSS72  = GND
  DQ14_A  = M_J_CPU1_SA_DQ<14>
  VSS73  = GND
  DQ15_A  = M_J_CPU1_SA_DQ<15>
  VSS74  = GND
  DQ18_A  = M_J_CPU1_SA_DQ<18>
  VSS75  = GND
  DQ19_A  = M_J_CPU1_SA_DQ<19>
  VSS76  = GND
  \dqs7_a_c||tdqs7_a_c\  = M_J_CPU1_SA_DQS_DN<7>
  \dqs7_a_t||tdqs7_a_t\  = M_J_CPU1_SA_DQS_DP<7>
  VSS77  = GND
  DQ22_A  = M_J_CPU1_SA_DQ<22>
  VSS78  = GND
  DQ23_A  = M_J_CPU1_SA_DQ<23>
  VSS79  = GND
  DQ26_A  = M_J_CPU1_SA_DQ<26>
  VSS80  = GND
  DQ27_A  = M_J_CPU1_SA_DQ<27>
  VSS81  = GND
  \dqs8_a_c||tdqs8_a_c\  = M_J_CPU1_SA_DQS_DN<8>
  \dqs8_a_t||tdqs8_a_t\  = M_J_CPU1_SA_DQS_DP<8>
  VSS82  = GND
  DQ30_A  = M_J_CPU1_SA_DQ<30>
  VSS83  = GND
  DQ31_A  = M_J_CPU1_SA_DQ<31>
  VSS84  = GND
  CB2_A  = M_J_CPU1_SA_CB<2>
  VSS85  = GND
  CB3_A  = M_J_CPU1_SA_CB<3>
  VSS86  = GND
  \dqs9_a_c||tdqs9_a_c\  = M_J_CPU1_SA_DQS_DN<9>
  \dqs9_a_t||tdqs9_a_t\  = M_J_CPU1_SA_DQS_DP<9>
  VSS87  = GND
  CB6_A  = M_J_CPU1_SA_CB<6>
  VSS88  = GND
  CB7_A  = M_J_CPU1_SA_CB<7>
  VSS89  = GND
  RESET_N  = M_J_CPU1_RESET_N
  VSS90  = GND
  CS1_A_N  = M_J_CPU1_SA_CS_N<1>
  VSS91  = GND
  CA1_A  = M_J_CPU1_SA_CA<1>
  VSS92  = GND
  CA3_A  = M_J_CPU1_SA_CA<3>
  VSS93  = GND
  CA5_A  = M_J_CPU1_SA_CA<5>
  VSS94  = GND
  CK_T  = M_J_CPU1_CLK_DP<0>
  CK_C  = M_J_CPU1_CLK_DN<0>
  VSS95  = GND
  RFU4  = NC
  CA1_B  = M_J_CPU1_SB_CA<1>
  VSS96  = GND
  CA3_B  = M_J_CPU1_SB_CA<3>
  VSS97  = GND
  CA5_B  = M_J_CPU1_SB_CA<5>
  VSS98  = GND
  PAR_B  = M_J_CPU1_SB_PAR
  VSS99  = GND
  CS1_B_N  = M_J_CPU1_SB_CS_N<1>
  VSS100  = GND
  RFU5  = NC
  RFU6  = NC
  VSS101  = GND
  CB6_B  = M_J_CPU1_SB_CB<6>
  VSS102  = GND
  CB7_B  = M_J_CPU1_SB_CB<7>
  VSS103  = GND
  DQS4_B_C  = M_J_CPU1_SB_DQS_DN<4>
  DQS4_B_T  = M_J_CPU1_SB_DQS_DP<4>
  VSS104  = GND
  CB2_B  = M_J_CPU1_SB_CB<2>
  VSS105  = GND
  CB3_B  = M_J_CPU1_SB_CB<3>
  VSS106  = GND
  DQ2_B  = M_J_CPU1_SB_DQ<2>
  VSS107  = GND
  DQ3_B  = M_J_CPU1_SB_DQ<3>
  VSS108  = GND
  \dqs5_b_c||tdqs5_b_c\  = M_J_CPU1_SB_DQS_DN<5>
  \dqs5_b_t||tdqs5_b_t\  = M_J_CPU1_SB_DQS_DP<5>
  VSS109  = GND
  DQ6_B  = M_J_CPU1_SB_DQ<6>
  VSS110  = GND
  DQ7_B  = M_J_CPU1_SB_DQ<7>
  VSS111  = GND
  DQ10_B  = M_J_CPU1_SB_DQ<10>
  VSS112  = GND
  DQ11_B  = M_J_CPU1_SB_DQ<11>
  VSS113  = GND
  \dqs6_b_c||tdqs6_b_c\  = M_J_CPU1_SB_DQS_DN<6>
  \dqs6_b_t||tdqs6_b_t\  = M_J_CPU1_SB_DQS_DP<6>
  VSS114  = GND
  DQ14_B  = M_J_CPU1_SB_DQ<14>
  VSS115  = GND
  DQ15_B  = M_J_CPU1_SB_DQ<15>
  VSS116  = GND
  DQ18_B  = M_J_CPU1_SB_DQ<18>
  VSS117  = GND
  DQ19_B  = M_J_CPU1_SB_DQ<19>
  VSS118  = GND
  \dqs7_b_c||tdqs7_b_c\  = M_J_CPU1_SB_DQS_DN<7>
  \dqs7_b_t||tdqs7_b_t\  = M_J_CPU1_SB_DQS_DP<7>
  VSS119  = GND
  DQ22_B  = M_J_CPU1_SB_DQ<22>
  VSS120  = GND
  DQ23_B  = M_J_CPU1_SB_DQ<23>
  VSS121  = GND
  DQ26_B  = M_J_CPU1_SB_DQ<26>
  VSS122  = GND
  DQ27_B  = M_J_CPU1_SB_DQ<27>
  VSS123  = GND
  \dqs8_b_c||tdqs8_b_c\  = M_J_CPU1_SB_DQS_DN<8>
  \dqs8_b_t||tdqs8_b_t\  = M_J_CPU1_SB_DQS_DP<8>
  VSS124  = GND
  DQ30_B  = M_J_CPU1_SB_DQ<30>
  VSS125  = GND
  DQ31_B  = M_J_CPU1_SB_DQ<31>
  VSS126  = GND
  G1  = GND
  G2  = GND
  G3  = GND

(kicad_pcb
	(version 20260206)
	(generator "pcbnew")
	(generator_version "10.0")
	(general
		(thickness 1.6)
		(legacy_teardrops no)
	)
	(paper "A4")
	(title_block
		(title "04192023_DAF0TMB3IC0_F0TG_MB_C_brd_V02_OCP.brd")
		(comment 1 "Grand Teton / footprint 1456 of 8354 (J29), pads 138-183 of 291")
	)
	(layers
		(0 "F.Cu" signal "TOP")
		(4 "In1.Cu" signal "GND")
		(6 "In2.Cu" signal "IN1")
		(8 "In3.Cu" signal "GND1")
		(10 "In4.Cu" signal "IN2")
		(12 "In5.Cu" signal "GND2")
		(14 "In6.Cu" signal "IN3")
		(16 "In7.Cu" signal "GND3")
		(18 "In8.Cu" signal "VCC")
		(20 "In9.Cu" signal "VCC1")
		(22 "In10.Cu" signal "GND4")
		(24 "In11.Cu" signal "IN4")
		(26 "In12.Cu" signal "GND5")
		(28 "In13.Cu" signal "IN5")
		(30 "In14.Cu" signal "GND6")
		(32 "In15.Cu" signal "IN6")
		(34 "In16.Cu" signal "GND7")
		(2 "B.Cu" signal "BOTTOM")
		(9 "F.Adhes" user "F.Adhesive")
		(11 "B.Adhes" user "B.Adhesive")
		(13 "F.Paste" user "Package Geometry/Pastemask Top")
		(15 "B.Paste" user "Package Geometry/Pastemask Bottom")
		(5 "F.SilkS" user "Ref Des/Silkscreen Top")
		(7 "B.SilkS" user "Ref Des/Silkscreen Bottom")
		(1 "F.Mask" user "Board Geometry/Soldermask Top")
		(3 "B.Mask" user "Board Geometry/Soldermask Bottom")
		(17 "Dwgs.User" user "User.Drawings")
		(19 "Cmts.User" user "User.Comments")
		(21 "Eco1.User" user "User.Eco1")
		(23 "Eco2.User" user "User.Eco2")
		(25 "Edge.Cuts" user "Board Geometry/Outline")
		(27 "Margin" user)
		(31 "F.CrtYd" user "Package Geometry/Place Bound Top")
		(29 "B.CrtYd" user "Package Geometry/Place Bound Bottom")
		(35 "F.Fab" user "Ref Des/Assembly Top")
		(33 "B.Fab" user "Ref Des/Assembly Bottom")
	)
	(footprint ""
		(layer "F.Cu")
		(at 189.110112 -255.560322 180)
		(property "Reference" "J29"
			(at -2.7178 -81.857088 0)
			(unlocked yes)
			(layer "F.SilkS")
			(effects
				(font
					(size 0.7874 0.5842)
					(thickness 0.1524)
				)
			)
		)
		(property "Value" ""
			(at 0 0 180)
			(layer "F.Fab")
			(effects
				(font
					(size 1.27 1.27)
				)
			)
		)
		(duplicate_pad_numbers_are_jumpers no)
		(pad "138" smd rect
			(at -2.050034 58.224928 90)
			(size 0.519938 1.4986)
			(layers "F.Cu" "F.Mask" "F.Paste")
			(net "M_J_CPU1_SB_DQS_DN<3>")
		)
		(pad "139" smd rect
			(at -2.050034 59.075066 90)
			(size 0.519938 1.4986)
			(layers "F.Cu" "F.Mask" "F.Paste")
			(net "GND")
		)
		(pad "140" smd rect
			(at -2.050034 59.92495 90)
			(size 0.519938 1.4986)
			(layers "F.Cu" "F.Mask" "F.Paste")
			(net "M_J_CPU1_SB_DQ<28>")
		)
		(pad "141" smd rect
			(at -2.050034 60.775088 90)
			(size 0.519938 1.4986)
			(layers "F.Cu" "F.Mask" "F.Paste")
			(net "GND")
		)
		(pad "142" smd rect
			(at -2.050034 61.624972 90)
			(size 0.519938 1.4986)
			(layers "F.Cu" "F.Mask" "F.Paste")
			(net "M_J_CPU1_SB_DQ<29>")
		)
		(pad "143" smd rect
			(at -2.050034 62.47511 90)
			(size 0.519938 1.4986)
			(layers "F.Cu" "F.Mask" "F.Paste")
			(net "GND")
		)
		(pad "144" smd rect
			(at -2.050034 63.324994 90)
			(size 0.519938 1.4986)
			(layers "F.Cu" "F.Mask" "F.Paste")
			(net "Net_2383")
		)
		(pad "145" smd rect
			(at 2.050034 -63.324994 90)
			(size 0.519938 1.4986)
			(layers "F.Cu" "F.Mask" "F.Paste")
			(net "P12V_MEM_CPU1")
		)
		(pad "146" smd rect
			(at 2.050034 -62.47511 90)
			(size 0.519938 1.4986)
			(layers "F.Cu" "F.Mask" "F.Paste")
			(net "P12V_MEM_CPU1")
		)
		(pad "147" smd rect
			(at 2.050034 -61.624972 90)
			(size 0.519938 1.4986)
			(layers "F.Cu" "F.Mask" "F.Paste")
			(net "PWRGD_CHJ_CPU1_DIMM")
		)
		(pad "148" smd rect
			(at 2.050034 -60.775088 90)
			(size 0.519938 1.4986)
			(layers "F.Cu" "F.Mask" "F.Paste")
			(net "PD_CHJ_CPU1_DIMM_SAA")
		)
		(pad "149" smd rect
			(at 2.050034 -59.92495 90)
			(size 0.519938 1.4986)
			(layers "F.Cu" "F.Mask" "F.Paste")
			(net "Net_2384")
		)
		(pad "150" smd rect
			(at 2.050034 -59.075066 90)
			(size 0.519938 1.4986)
			(layers "F.Cu" "F.Mask" "F.Paste")
			(net "Net_2385")
		)
		(pad "151" smd rect
			(at 2.050034 -58.224928 90)
			(size 0.519938 1.4986)
			(layers "F.Cu" "F.Mask" "F.Paste")
			(net "GND")
		)
		(pad "152" smd rect
			(at 2.050034 -57.375044 90)
			(size 0.519938 1.4986)
			(layers "F.Cu" "F.Mask" "F.Paste")
			(net "M_J_CPU1_SA_DQ<2>")
		)
		(pad "153" smd rect
			(at 2.050034 -56.524906 90)
			(size 0.519938 1.4986)
			(layers "F.Cu" "F.Mask" "F.Paste")
			(net "GND")
		)
		(pad "154" smd rect
			(at 2.050034 -55.675022 90)
			(size 0.519938 1.4986)
			(layers "F.Cu" "F.Mask" "F.Paste")
			(net "M_J_CPU1_SA_DQ<3>")
		)
		(pad "155" smd rect
			(at 2.050034 -54.824884 90)
			(size 0.519938 1.4986)
			(layers "F.Cu" "F.Mask" "F.Paste")
			(net "GND")
		)
		(pad "156" smd rect
			(at 2.050034 -53.975 90)
			(size 0.519938 1.4986)
			(layers "F.Cu" "F.Mask" "F.Paste")
			(net "M_J_CPU1_SA_DQS_DN<5>")
		)
		(pad "157" smd rect
			(at 2.050034 -53.125116 90)
			(size 0.519938 1.4986)
			(layers "F.Cu" "F.Mask" "F.Paste")
			(net "M_J_CPU1_SA_DQS_DP<5>")
		)
		(pad "158" smd rect
			(at 2.050034 -52.274978 90)
			(size 0.519938 1.4986)
			(layers "F.Cu" "F.Mask" "F.Paste")
			(net "GND")
		)
		(pad "159" smd rect
			(at 2.050034 -51.425094 90)
			(size 0.519938 1.4986)
			(layers "F.Cu" "F.Mask" "F.Paste")
			(net "M_J_CPU1_SA_DQ<6>")
		)
		(pad "160" smd rect
			(at 2.050034 -50.574956 90)
			(size 0.519938 1.4986)
			(layers "F.Cu" "F.Mask" "F.Paste")
			(net "GND")
		)
		(pad "161" smd rect
			(at 2.050034 -49.725072 90)
			(size 0.519938 1.4986)
			(layers "F.Cu" "F.Mask" "F.Paste")
			(net "M_J_CPU1_SA_DQ<7>")
		)
		(pad "162" smd rect
			(at 2.050034 -48.874934 90)
			(size 0.519938 1.4986)
			(layers "F.Cu" "F.Mask" "F.Paste")
			(net "GND")
		)
		(pad "163" smd rect
			(at 2.050034 -48.02505 90)
			(size 0.519938 1.4986)
			(layers "F.Cu" "F.Mask" "F.Paste")
			(net "M_J_CPU1_SA_DQ<10>")
		)
		(pad "164" smd rect
			(at 2.050034 -47.174912 90)
			(size 0.519938 1.4986)
			(layers "F.Cu" "F.Mask" "F.Paste")
			(net "GND")
		)
		(pad "165" smd rect
			(at 2.050034 -46.325028 90)
			(size 0.519938 1.4986)
			(layers "F.Cu" "F.Mask" "F.Paste")
			(net "M_J_CPU1_SA_DQ<11>")
		)
		(pad "166" smd rect
			(at 2.050034 -45.47489 90)
			(size 0.519938 1.4986)
			(layers "F.Cu" "F.Mask" "F.Paste")
			(net "GND")
		)
		(pad "167" smd rect
			(at 2.050034 -44.625006 90)
			(size 0.519938 1.4986)
			(layers "F.Cu" "F.Mask" "F.Paste")
			(net "M_J_CPU1_SA_DQS_DN<6>")
		)
		(pad "168" smd rect
			(at 2.050034 -43.775122 90)
			(size 0.519938 1.4986)
			(layers "F.Cu" "F.Mask" "F.Paste")
			(net "M_J_CPU1_SA_DQS_DP<6>")
		)
		(pad "169" smd rect
			(at 2.050034 -42.924984 90)
			(size 0.519938 1.4986)
			(layers "F.Cu" "F.Mask" "F.Paste")
			(net "GND")
		)
		(pad "170" smd rect
			(at 2.050034 -42.0751 90)
			(size 0.519938 1.4986)
			(layers "F.Cu" "F.Mask" "F.Paste")
			(net "M_J_CPU1_SA_DQ<14>")
		)
		(pad "171" smd rect
			(at 2.050034 -41.224962 90)
			(size 0.519938 1.4986)
			(layers "F.Cu" "F.Mask" "F.Paste")
			(net "GND")
		)
		(pad "172" smd rect
			(at 2.050034 -40.375078 90)
			(size 0.519938 1.4986)
			(layers "F.Cu" "F.Mask" "F.Paste")
			(net "M_J_CPU1_SA_DQ<15>")
		)
		(pad "173" smd rect
			(at 2.050034 -39.52494 90)
			(size 0.519938 1.4986)
			(layers "F.Cu" "F.Mask" "F.Paste")
			(net "GND")
		)
		(pad "174" smd rect
			(at 2.050034 -38.675056 90)
			(size 0.519938 1.4986)
			(layers "F.Cu" "F.Mask" "F.Paste")
			(net "M_J_CPU1_SA_DQ<18>")
		)
		(pad "175" smd rect
			(at 2.050034 -37.824918 90)
			(size 0.519938 1.4986)
			(layers "F.Cu" "F.Mask" "F.Paste")
			(net "GND")
		)
		(pad "176" smd rect
			(at 2.050034 -36.975034 90)
			(size 0.519938 1.4986)
			(layers "F.Cu" "F.Mask" "F.Paste")
			(net "M_J_CPU1_SA_DQ<19>")
		)
		(pad "177" smd rect
			(at 2.050034 -36.124896 90)
			(size 0.519938 1.4986)
			(layers "F.Cu" "F.Mask" "F.Paste")
			(net "GND")
		)
		(pad "178" smd rect
			(at 2.050034 -35.275012 90)
			(size 0.519938 1.4986)
			(layers "F.Cu" "F.Mask" "F.Paste")
			(net "M_J_CPU1_SA_DQS_DN<7>")
		)
		(pad "179" smd rect
			(at 2.050034 -34.425128 90)
			(size 0.519938 1.4986)
			(layers "F.Cu" "F.Mask" "F.Paste")
			(net "M_J_CPU1_SA_DQS_DP<7>")
		)
		(pad "180" smd rect
			(at 2.050034 -33.57499 90)
			(size 0.519938 1.4986)
			(layers "F.Cu" "F.Mask" "F.Paste")
			(net "GND")
		)
		(pad "181" smd rect
			(at 2.050034 -32.725106 90)
			(size 0.519938 1.4986)
			(layers "F.Cu" "F.Mask" "F.Paste")
			(net "M_J_CPU1_SA_DQ<22>")
		)
		(pad "182" smd rect
			(at 2.050034 -31.874968 90)
			(size 0.519938 1.4986)
			(layers "F.Cu" "F.Mask" "F.Paste")
			(net "GND")
		)
		(pad "183" smd rect
			(at 2.050034 -31.025084 90)
			(size 0.519938 1.4986)
			(layers "F.Cu" "F.Mask" "F.Paste")
			(net "M_J_CPU1_SA_DQ<23>")
		)
	)
)
